FILE_TYPE = CONNECTIVITY;
{Allegro Design Entry HDL 17.2-2016 S081 (4005846) 1/11/2022}
"PAGE_NUMBER" = 322;
0"NC";
1"P3V3\g";
2"P3V3\g";
3"P3V3_AUX\g";
4"P3V3_AUX\g";
5"P3V3_AUX\g";
6"PVNN_TERM_CPU0\g";
7"PVNN_TERM_CPU0\g";
8"PVNN_TERM_CPU0\g";
9"P3V3_AUX\g";
10"GND\g";
11"GND\g";
12"GND\g";
13"GND\g";
14"GND\g";
15"GND\g";
16"GND\g";
17"GND\g";
18"GND\g";
19"GND\g";
20"GND\g";
21"GND\g";
22"GND\g";
23"H_CPU_ERR0_LVC1_N"CDS_PHYS_NET_NAME"H_CPU_ERR0_LVC1_N";
24"P0V62_CPU1_RST_DDR_VREF";
25"PD_GTL2014_BMC_JTAG_DIR_1";
26"RST_CPU1_DRAM_GH_PLD_LVT3_R_N"CDS_PHYS_NET_NAME"RST_CPU0_DRAM_GH_PLD_N";
27"RST_CPU1_DRAM_EF_PLD_LVT3_R_N"CDS_PHYS_NET_NAME"RST_CPU0_DRAM_EF_PLD_N";
28"RST_CPU1_DRAM_CD_PLD_LVT3_R_N"CDS_PHYS_NET_NAME"RST_CPU0_DRAM_CD_PLD_N";
29"RST_CPU1_DRAM_AB_PLD_LVT3_R_N"CDS_PHYS_NET_NAME"RST_CPU0_DRAM_AB_PLD_N";
30"RST_CPU1_DRAM_AB_PLD_N"CDS_PHYS_NET_NAME"RST_CPU1_DRAM_AB_PLD_N";
31"RST_CPU1_DRAM_CD_PLD_N"CDS_PHYS_NET_NAME"RST_CPU1_DRAM_CD_PLD_N";
32"RST_CPU1_DRAM_EF_PLD_N"CDS_PHYS_NET_NAME"RST_CPU1_DRAM_EF_PLD_N";
33"RST_CPU1_DRAM_GH_PLD_N"CDS_PHYS_NET_NAME"RST_CPU1_DRAM_GH_PLD_N";
34"H_CPU_ERR1_LVC1_N"CDS_PHYS_NET_NAME"H_CPU_ERR1_LVC1_N";
35"P0V62_CPU0_ERRS_U306_VREF";
36"H_CPU_ERR0_LVC2_R_N"CDS_PHYS_NET_NAME"RST_CPU0_DRAM_AB_PLD_N";
37"H_CPU_ERR1_LVC2_R_N"CDS_PHYS_NET_NAME"RST_CPU0_DRAM_CD_PLD_N";
38"H_CPU_ERR1_PCH_R_N";
39"H_CPU_ERR1_LVC2_N"CDS_PHYS_NET_NAME"RST_CPU0_DRAM_CD_PLD_N";
40"RST_CPU1_DRAM_CD_PLD_LVT3_N"CDS_PHYS_NET_NAME"RST_CPU0_DRAM_CD_PLD_N";
41"RST_CPU1_DRAM_GH_PLD_LVT3_N"CDS_PHYS_NET_NAME"RST_CPU0_DRAM_GH_PLD_N";
42"RST_CPU0_DRAM_EF_PLD_N"CDS_PHYS_NET_NAME"RST_CPU0_DRAM_EF_PLD_N";
43"RST_CPU0_DRAM_GH_PLD_N"CDS_PHYS_NET_NAME"RST_CPU0_DRAM_GH_PLD_N";
44"PD_GTL2014_BMC_JTAG_DIR_0";
45"P0V62_CPU0_RST_DDR_VREF";
46"RST_CPU0_DRAM_EF_PLD_LVT3_R_N"CDS_PHYS_NET_NAME"RST_CPU0_DRAM_EF_PLD_N";
47"RST_CPU0_DRAM_AB_PLD_LVT3_R_N"CDS_PHYS_NET_NAME"RST_CPU0_DRAM_AB_PLD_N";
48"NC_U306_A0";
49"H_CPU_ERR2_LVC2_R_N"CDS_PHYS_NET_NAME"RST_CPU0_DRAM_EF_PLD_N";
50"PD_CPU1_ERRS_U306_DIR";
51"PD_GTL2014_ERROR_B0";
52"RST_CPU0_DRAM_AB_PLD_N"CDS_PHYS_NET_NAME"RST_CPU0_DRAM_AB_PLD_N";
53"RST_CPU0_DRAM_CD_PLD_N"CDS_PHYS_NET_NAME"RST_CPU0_DRAM_CD_PLD_N";
54"H_CPU_ERR0_PCH_R_N";
55"H_CPU_ERR0_LVC2_N"CDS_PHYS_NET_NAME"H_CPU_ERR0_LVC2_N";
56"H_CPU_ERR2_LVC2_N"CDS_PHYS_NET_NAME"H_CPU_ERR2_LVC2_N";
57"H_CPU_ERR2_PCH_R_N";
58"RST_CPU0_DRAM_GH_PLD_LVT3_R_N"CDS_PHYS_NET_NAME"RST_CPU0_DRAM_GH_PLD_N";
59"RST_CPU0_DRAM_CD_PLD_LVT3_R_N"CDS_PHYS_NET_NAME"RST_CPU0_DRAM_CD_PLD_N";
60"RST_CPU1_DRAM_AB_PLD_LVT3_N"CDS_PHYS_NET_NAME"RST_CPU0_DRAM_AB_PLD_N";
61"H_CPU_ERR2_LVC1_N"CDS_PHYS_NET_NAME"H_CPU_ERR2_LVC1_N";
62"H_CPU_ERR0_LVC1_R_N";
63"H_CPU_ERR2_LVC1_R_N";
64"H_CPU1_ERR2_LVC1_R_N";
65"H_CPU1_ERR0_LVC1_R_N";
66"H_CPU_ERR1_LVC1_R_N";
67"H_CPU0_ERR0_LVC1_R_N";
68"H_CPU0_ERR1_LVC1_R_N";
69"H_CPU1_ERR1_LVC1_R_N";
70"H_CPU0_ERR2_LVC1_R_N";
71"RST_CPU0_DRAM_GH_PLD_LVT3_N"CDS_PHYS_NET_NAME"RST_CPU0_DRAM_GH_PLD_N";
72"RST_CPU0_DRAM_AB_PLD_LVT3_N"CDS_PHYS_NET_NAME"RST_CPU0_DRAM_AB_PLD_N";
73"RST_CPU0_DRAM_CD_PLD_LVT3_N"CDS_PHYS_NET_NAME"RST_CPU0_DRAM_CD_PLD_N";
74"RST_CPU0_DRAM_EF_PLD_LVT3_N"CDS_PHYS_NET_NAME"RST_CPU0_DRAM_EF_PLD_N";
75"RST_CPU1_DRAM_EF_PLD_LVT3_N"CDS_PHYS_NET_NAME"RST_CPU0_DRAM_EF_PLD_N";
%"UNIVERSAL_GND"
"1","(-8825,2075)","0","logical_power","I10";
;
CDS_LIB"logical_power"
HDL_POWER"GND";
"A"21;
%"Q_CAP"
"1","(-8225,2175)","2","pure_quanta","I101";
;
PART_NUMBER"CH4104K1B00"
TOLERANCE"10%"
VOLTAGE"25V"
MATERIAL"X7R"
PACK_TYPE"0402"
VALUE"0.1UF"
$LOCATION"C2252"
CDS_LIB"pure_quanta"
CDS_LOCATION"C2252"
$SEC"1"
CDS_SEC"1";
"B"
$PN"2"13;
"A"
$PN"1"45;
%"UNIVERSAL_GND"
"1","(-7850,1900)","2","logical_power","I102";
;
CDS_LIB"logical_power"
HDL_POWER"GND";
"A"13;
%"UNIVERSAL_POWER"
"1","(-7850,2800)","0","logical_power","I105";
;
HDL_POWER"P3V3_AUX"
CDS_LIB"logical_power";
"A"3;
%"Q_CAP"
"1","(-8225,100)","2","pure_quanta","I106";
;
PART_NUMBER"CH4104K1B00"
MATERIAL"X7R"
VOLTAGE"25V"
TOLERANCE"10%"
PACK_TYPE"0402"
VALUE"0.1UF"
$LOCATION"C2253"
CDS_LIB"pure_quanta"
CDS_LOCATION"C2253"
$SEC"1"
CDS_SEC"1";
"B"
$PN"2"12;
"A"
$PN"1"24;
%"UNIVERSAL_GND"
"1","(-7850,-175)","2","logical_power","I107";
;
CDS_LIB"logical_power"
HDL_POWER"GND";
"A"12;
%"UNIVERSAL_POWER"
"1","(-8975,2550)","0","logical_power","I11";
;
HDL_POWER"P3V3_AUX"
CDS_LIB"logical_power";
"A"9;
%"UNIVERSAL_POWER"
"1","(-7850,725)","0","logical_power","I110";
;
HDL_POWER"P3V3_AUX"
CDS_LIB"logical_power";
"A"5;
%"Q_CAP"
"1","(-8225,-1800)","2","pure_quanta","I111";
;
PART_NUMBER"CH4104K1B00"
VALUE"0.1UF"
PACK_TYPE"0402"
VOLTAGE"25V"
TOLERANCE"10%"
MATERIAL"X7R"
$LOCATION"C2254"
CDS_LIB"pure_quanta"
CDS_LOCATION"C2254"
$SEC"1"
CDS_SEC"1";
"B"
$PN"2"10;
"A"
$PN"1"35;
%"UNIVERSAL_GND"
"1","(-7850,-2075)","2","logical_power","I112";
;
CDS_LIB"logical_power"
HDL_POWER"GND";
"A"10;
%"UNIVERSAL_POWER"
"1","(-7850,-1200)","0","logical_power","I115";
;
HDL_POWER"P3V3"
CDS_LIB"logical_power";
"A"2;
%"Q_RES"
"2","(-7850,2550)","0","pure_quanta","I128";
;
PART_NUMBER"CS24322FB03"
VALUE"4.32K"
TOLERANCE"1%"
WATTAGE"1/16W"
MATERIAL"CHIP"
PACK_TYPE"0402LF"
LOCATION"R4036"
CDS_LIB"pure_quanta"
$SEC"1"
CDS_SEC"1";
"A"
$PN"1"3;
"B"
$PN"2"45;
%"Q_RES"
"2","(-7850,2175)","0","pure_quanta","I129";
;
PART_NUMBER"CS21002FB06"
VALUE"1K"
TOLERANCE"1%"
PACK_TYPE"0402LF"
MATERIAL"CHIP"
WATTAGE"1/16W"
LOCATION"R4039"
CDS_LIB"pure_quanta"
$SEC"1"
CDS_SEC"1";
"A"
$PN"1"45;
"B"
$PN"2"13;
%"Q_RES"
"2","(-7850,475)","0","pure_quanta","I130";
;
PART_NUMBER"CS24322FB03"
MATERIAL"CHIP"
VALUE"4.32K"
TOLERANCE"1%"
WATTAGE"1/16W"
PACK_TYPE"0402LF"
LOCATION"R4037"
CDS_LIB"pure_quanta"
$SEC"1"
CDS_SEC"1";
"A"
$PN"1"5;
"B"
$PN"2"24;
%"Q_RES"
"2","(-7850,100)","0","pure_quanta","I131";
;
PART_NUMBER"CS21002FB06"
VALUE"1K"
TOLERANCE"1%"
WATTAGE"1/16W"
MATERIAL"CHIP"
PACK_TYPE"0402LF"
LOCATION"R4040"
CDS_LIB"pure_quanta"
$SEC"1"
CDS_SEC"1";
"A"
$PN"1"24;
"B"
$PN"2"12;
%"UNIVERSAL_POWER"
"1","(-12050,-850)","0","logical_power","I132";
;
HDL_POWER"PVNN_TERM_CPU0"
CDS_LIB"logical_power";
"A"7;
%"Q_RES"
"1","(-12400,-3100)","0","pure_quanta","I157";
;
PART_NUMBER"CS00002JB13"
TOLERANCE"5%"
VALUE"0"
$LOCATION"R344"
PACK_TYPE"0402LF"
CDS_LIB"pure_quanta"
MATERIAL"CHIP"
WATTAGE"1/16W"
CDS_LOCATION"R344"
$SEC"1"
CDS_SEC"1";
"B"
$PN"2"63;
"A"
$PN"1"70;
%"Q_RES"
"1","(-12400,-3150)","0","pure_quanta","I158";
;
PART_NUMBER"CS00002JB13"
TOLERANCE"5%"
VALUE"0"
$LOCATION"R345"
CDS_LIB"pure_quanta"
WATTAGE"1/16W"
MATERIAL"CHIP"
PACK_TYPE"0402LF"
CDS_LOCATION"R345"
$SEC"1"
CDS_SEC"1";
"B"
$PN"2"63;
"A"
$PN"1"64;
%"Q_RES"
"1","(-12450,-1325)","0","pure_quanta","I159";
;
PART_NUMBER"CS00002JB13"
WATTAGE"1/16W"
MATERIAL"CHIP"
VALUE"0"
PACK_TYPE"0402LF"
TOLERANCE"5%"
$LOCATION"R336"
CDS_LIB"pure_quanta"
CDS_LOCATION"R336"
$SEC"1"
CDS_SEC"1";
"B"
$PN"2"62;
"A"
$PN"1"67;
%"Q_RES"
"1","(-12450,-1375)","0","pure_quanta","I160";
;
PART_NUMBER"CS00002JB13"
VALUE"0"
TOLERANCE"5%"
$LOCATION"R337"
WATTAGE"1/16W"
MATERIAL"CHIP"
PACK_TYPE"0402LF"
CDS_LIB"pure_quanta"
CDS_LOCATION"R337"
$SEC"1"
CDS_SEC"1";
"B"
$PN"2"62;
"A"
$PN"1"65;
%"Q_RES"
"1","(-12475,-2300)","0","pure_quanta","I163";
;
PART_NUMBER"CS00002JB13"
VALUE"0"
TOLERANCE"5%"
$LOCATION"R341"
WATTAGE"1/16W"
MATERIAL"CHIP"
CDS_LIB"pure_quanta"
PACK_TYPE"0402LF"
CDS_LOCATION"R341"
$SEC"1"
CDS_SEC"1";
"B"
$PN"2"66;
"A"
$PN"1"69;
%"Q_RES"
"1","(-12475,-2250)","0","pure_quanta","I164";
;
PART_NUMBER"CS00002JB13"
VALUE"0"
TOLERANCE"5%"
$LOCATION"R340"
PACK_TYPE"0402LF"
CDS_LIB"pure_quanta"
MATERIAL"CHIP"
WATTAGE"1/16W"
CDS_LOCATION"R340"
$SEC"1"
CDS_SEC"1";
"B"
$PN"2"66;
"A"
$PN"1"68;
%"Q_RES"
"2","(-12050,-1050)","0","pure_quanta","I169";
;
PART_NUMBER"CS11502FB07"
VALUE"150"
MATERIAL"CHIP"
TOLERANCE"1%"
PACK_TYPE"0402LF"
WATTAGE"1/16W"
$LOCATION"R4390"
CDS_LIB"pure_quanta"
CDS_LOCATION"R4390"
$SEC"1"
CDS_SEC"1";
"A"
$PN"1"7;
"B"
$PN"2"62;
%"Q_RES"
"1","(-11325,-3150)","0","pure_quanta","I171";
;
PART_NUMBER"CS00002JB13"
TOLERANCE"5%"
VALUE"0"
LOCATION"R346"
CDS_LIB"pure_quanta"
WATTAGE"1/16W"
MATERIAL"CHIP"
PACK_TYPE"0402LF"
$SEC"1"
CDS_SEC"1";
"B"
$PN"2"61;
"A"
$PN"1"63;
%"Q_RES"
"1","(-11325,-2300)","0","pure_quanta","I172";
;
PART_NUMBER"CS00002JB13"
TOLERANCE"5%"
VALUE"0"
LOCATION"R342"
CDS_LIB"pure_quanta"
PACK_TYPE"0402LF"
MATERIAL"CHIP"
WATTAGE"1/16W"
$SEC"1"
CDS_SEC"1";
"B"
$PN"2"34;
"A"
$PN"1"66;
%"Q_RES"
"1","(-11325,-1375)","0","pure_quanta","I173";
;
PART_NUMBER"CS00002JB13"
TOLERANCE"5%"
VALUE"0"
LOCATION"R338"
CDS_LIB"pure_quanta"
WATTAGE"1/16W"
MATERIAL"CHIP"
PACK_TYPE"0402LF"
$SEC"1"
CDS_SEC"1";
"B"
$PN"2"23;
"A"
$PN"1"62;
%"Q_RES"
"2","(-12075,-1975)","0","pure_quanta","I174";
;
PART_NUMBER"CS11502FB07"
PACK_TYPE"0402LF"
TOLERANCE"1%"
WATTAGE"1/16W"
MATERIAL"CHIP"
VALUE"150"
$LOCATION"R4388"
CDS_LIB"pure_quanta"
CDS_LOCATION"R4388"
$SEC"1"
CDS_SEC"1";
"A"
$PN"1"8;
"B"
$PN"2"66;
%"UNIVERSAL_POWER"
"1","(-12075,-1775)","0","logical_power","I175";
;
HDL_POWER"PVNN_TERM_CPU0"
CDS_LIB"logical_power";
"A"8;
%"UNIVERSAL_POWER"
"1","(-12075,-2625)","0","logical_power","I176";
;
HDL_POWER"PVNN_TERM_CPU0"
CDS_LIB"logical_power";
"A"6;
%"Q_RES"
"2","(-12075,-2825)","0","pure_quanta","I177";
;
PART_NUMBER"CS11502FB07"
TOLERANCE"1%"
MATERIAL"CHIP"
WATTAGE"1/16W"
PACK_TYPE"0402LF"
VALUE"150"
$LOCATION"R4389"
CDS_LIB"pure_quanta"
CDS_LOCATION"R4389"
$SEC"1"
CDS_SEC"1";
"A"
$PN"1"6;
"B"
$PN"2"63;
%"Q_RES"
"2","(-7850,-1800)","0","pure_quanta","I181";
;
PART_NUMBER"CS21002FB06"
VALUE"1K"
TOLERANCE"1%"
WATTAGE"1/16W"
PACK_TYPE"0402LF"
MATERIAL"CHIP"
LOCATION"R4041"
CDS_LIB"pure_quanta"
$SEC"1"
CDS_SEC"1";
"A"
$PN"1"35;
"B"
$PN"2"10;
%"Q_RES"
"2","(-7850,-1425)","0","pure_quanta","I182";
;
PART_NUMBER"CS24322FB03"
MATERIAL"CHIP"
PACK_TYPE"0402LF"
WATTAGE"1/16W"
TOLERANCE"1%"
VALUE"4.32K"
LOCATION"R4038"
CDS_LIB"pure_quanta"
$SEC"1"
CDS_SEC"1";
"A"
$PN"1"2;
"B"
$PN"2"35;
%"Q_RES"
"1","(-5800,-1875)","0","pure_quanta","I183";
;
PART_NUMBER"CS03322FB03"
VALUE"33.2"
MATERIAL"CHIP"
$LOCATION"R4392"
CDS_LIB"pure_quanta"
PACK_TYPE"0402LF"
TOLERANCE"1%"
WATTAGE"1/16W"
CDS_LOCATION"R4392"
$SEC"1"
CDS_SEC"1";
"B"
$PN"2"54;
"A"
$PN"1"36;
%"Q_RES"
"1","(-5800,-1800)","0","pure_quanta","I184";
;
PART_NUMBER"CS03322FB03"
VALUE"33.2"
MATERIAL"CHIP"
$LOCATION"R4050"
PACK_TYPE"0402LF"
TOLERANCE"1%"
WATTAGE"1/16W"
CDS_LIB"pure_quanta"
CDS_LOCATION"R4050"
$SEC"1"
CDS_SEC"1";
"B"
$PN"2"55;
"A"
$PN"1"36;
%"Q_RES"
"1","(-5800,-2800)","0","pure_quanta","I187";
;
PART_NUMBER"CS03322FB03"
VALUE"33.2"
MATERIAL"CHIP"
$LOCATION"R4052"
CDS_LIB"pure_quanta"
PACK_TYPE"0402LF"
TOLERANCE"1%"
WATTAGE"1/16W"
CDS_LOCATION"R4052"
$SEC"1"
CDS_SEC"1";
"B"
$PN"2"56;
"A"
$PN"1"49;
%"Q_RES"
"1","(-5800,-2375)","0","pure_quanta","I188";
;
PART_NUMBER"CS03322FB03"
MATERIAL"CHIP"
VALUE"33.2"
$LOCATION"R4393"
WATTAGE"1/16W"
TOLERANCE"1%"
PACK_TYPE"0402LF"
CDS_LIB"pure_quanta"
CDS_LOCATION"R4393"
$SEC"1"
CDS_SEC"1";
"B"
$PN"2"38;
"A"
$PN"1"37;
%"Q_RES"
"1","(-5800,-2875)","0","pure_quanta","I189";
;
PART_NUMBER"CS03322FB03"
MATERIAL"CHIP"
VALUE"33.2"
$LOCATION"R4394"
PACK_TYPE"0402LF"
TOLERANCE"1%"
WATTAGE"1/16W"
CDS_LIB"pure_quanta"
CDS_LOCATION"R4394"
$SEC"1"
CDS_SEC"1";
"B"
$PN"2"57;
"A"
$PN"1"49;
%"Q_RES"
"2","(-10425,-3025)","0","pure_quanta","I190";
;
PART_NUMBER"CS11502FB07"
MATERIAL"CHIP"
WATTAGE"1/16W"
TOLERANCE"1%"
VALUE"150"
PACK_TYPE"0402LF"
$LOCATION"R4391"
CDS_LIB"pure_quanta"
CDS_LOCATION"R4391"
$SEC"1"
CDS_SEC"1";
"A"
$PN"1"51;
"B"
$PN"2"11;
%"UNIVERSAL_GND"
"1","(-10425,-3250)","0","logical_power","I191";
;
HDL_POWER"GND"
CDS_LIB"logical_power";
"A"11;
%"UNIVERSAL_GND"
"1","(-7125,1800)","2","logical_power","I20";
;
CDS_LIB"logical_power"
HDL_POWER"GND";
"A"22;
%"GTL2014PW"
"1","(-9475,1675)","2","pure_quanta","I27";
;
PART_NUMBER"AL002014K01"
MATERIAL"IC"
PART_TYPE"SMLF"
VALUE"GTL2014PW"
$LOCATION"U304"
NEEDS_NO_SIZE"TRUE"
CDS_LMAN_SYM_OUTLINE"-250,350,250,-350"
CDS_LIB"pure_quanta"
SEC_TYPE""
CDS_LOCATION"U304"
SEC"1";
"VCC"
$PN"14"9;
"VREF"
$PN"4"45;
"DIR"
$PN"1"44;
"A0"
$PN"13"58;
"A1"
$PN"12"46;
"A2"
$PN"10"59;
"A3"
$PN"9"47;
"GND_0"
$PN"7"20;
"GND_1"
$PN"8"20;
"GND_2"
$PN"11"20;
"B3"
$PN"6"52;
"B2"
$PN"5"53;
"B1"
$PN"3"42;
"B0"
$PN"2"43;
%"Q_RES"
"1","(-7700,1575)","0","pure_quanta","I36";
;
PART_NUMBER"CS03322FB03"
TOLERANCE"1%"
MATERIAL"CHIP"
VALUE"33.2"
WATTAGE"1/16W"
PACK_TYPE"0402LF"
$LOCATION"R4045"
CDS_LIB"pure_quanta"
CDS_LOCATION"R4045"
$SEC"1"
CDS_SEC"1";
"B"
$PN"2"71;
"A"
$PN"1"58;
%"Q_RES"
"1","(-7700,1625)","0","pure_quanta","I37";
;
PART_NUMBER"CS03322FB03"
VALUE"33.2"
MATERIAL"CHIP"
$LOCATION"R4044"
WATTAGE"1/16W"
TOLERANCE"1%"
PACK_TYPE"0402LF"
CDS_LIB"pure_quanta"
CDS_LOCATION"R4044"
$SEC"1"
CDS_SEC"1";
"B"
$PN"2"74;
"A"
$PN"1"46;
%"Q_RES"
"1","(-7700,1675)","0","pure_quanta","I38";
;
PART_NUMBER"CS03322FB03"
VALUE"33.2"
MATERIAL"CHIP"
$LOCATION"R4043"
WATTAGE"1/16W"
TOLERANCE"1%"
PACK_TYPE"0402LF"
CDS_LIB"pure_quanta"
CDS_LOCATION"R4043"
$SEC"1"
CDS_SEC"1";
"B"
$PN"2"73;
"A"
$PN"1"59;
%"Q_RES"
"1","(-7700,1725)","0","pure_quanta","I39";
;
PART_NUMBER"CS03322FB03"
VALUE"33.2"
MATERIAL"CHIP"
$LOCATION"R4042"
PACK_TYPE"0402LF"
TOLERANCE"1%"
WATTAGE"1/16W"
CDS_LIB"pure_quanta"
CDS_LOCATION"R4042"
$SEC"1"
CDS_SEC"1";
"B"
$PN"2"72;
"A"
$PN"1"47;
%"GTL2014PW"
"1","(-9475,-400)","2","pure_quanta","I44";
;
PART_NUMBER"AL002014K01"
MATERIAL"IC"
VALUE"GTL2014PW"
PART_TYPE"SMLF"
$LOCATION"U305"
SEC_TYPE""
CDS_LIB"pure_quanta"
CDS_LMAN_SYM_OUTLINE"-250,350,250,-350"
NEEDS_NO_SIZE"TRUE"
CDS_LOCATION"U305"
SEC"1";
"VCC"
$PN"14"4;
"VREF"
$PN"4"24;
"DIR"
$PN"1"25;
"A0"
$PN"13"26;
"A1"
$PN"12"27;
"A2"
$PN"10"28;
"A3"
$PN"9"29;
"GND_0"
$PN"7"14;
"GND_1"
$PN"8"14;
"GND_2"
$PN"11"14;
"B3"
$PN"6"30;
"B2"
$PN"5"31;
"B1"
$PN"3"32;
"B0"
$PN"2"33;
%"UNIVERSAL_GND"
"1","(-7125,-275)","2","logical_power","I49";
;
CDS_LIB"logical_power"
HDL_POWER"GND";
"A"16;
%"Q_RES"
"1","(-7700,-350)","0","pure_quanta","I52";
;
PART_NUMBER"CS03322FB03"
MATERIAL"CHIP"
VALUE"33.2"
$LOCATION"R4046"
PACK_TYPE"0402LF"
TOLERANCE"1%"
WATTAGE"1/16W"
CDS_LIB"pure_quanta"
CDS_LOCATION"R4046"
$SEC"1"
CDS_SEC"1";
"B"
$PN"2"60;
"A"
$PN"1"29;
%"Q_RES"
"1","(-7700,-400)","0","pure_quanta","I53";
;
PART_NUMBER"CS03322FB03"
VALUE"33.2"
MATERIAL"CHIP"
$LOCATION"R4047"
WATTAGE"1/16W"
TOLERANCE"1%"
PACK_TYPE"0402LF"
CDS_LIB"pure_quanta"
CDS_LOCATION"R4047"
$SEC"1"
CDS_SEC"1";
"B"
$PN"2"40;
"A"
$PN"1"28;
%"Q_RES"
"1","(-7700,-500)","0","pure_quanta","I54";
;
PART_NUMBER"CS03322FB03"
MATERIAL"CHIP"
TOLERANCE"1%"
VALUE"33.2"
PACK_TYPE"0402LF"
WATTAGE"1/16W"
$LOCATION"R4049"
CDS_LIB"pure_quanta"
CDS_LOCATION"R4049"
$SEC"1"
CDS_SEC"1";
"B"
$PN"2"41;
"A"
$PN"1"26;
%"Q_RES"
"1","(-7700,-450)","0","pure_quanta","I55";
;
PART_NUMBER"CS03322FB03"
VALUE"33.2"
MATERIAL"CHIP"
$LOCATION"R4048"
WATTAGE"1/16W"
TOLERANCE"1%"
PACK_TYPE"0402LF"
CDS_LIB"pure_quanta"
CDS_LOCATION"R4048"
$SEC"1"
CDS_SEC"1";
"B"
$PN"2"75;
"A"
$PN"1"27;
%"UNIVERSAL_GND"
"1","(-8825,0)","0","logical_power","I58";
;
CDS_LIB"logical_power"
HDL_POWER"GND";
"A"15;
%"Q_CAP"
"1","(-8825,225)","0","pure_quanta","I59";
;
PART_NUMBER"CH5104KEB02"
TOLERANCE"10%"
VALUE"1UF"
VOLTAGE"25V"
PACK_TYPE"C0402"
MATERIAL"X6S"
$LOCATION"C2247"
CDS_LIB"pure_quanta"
CDS_LOCATION"C2247"
$SEC"1"
CDS_SEC"1";
"B"
$PN"2"15;
"A"
$PN"1"4;
%"UNIVERSAL_POWER"
"1","(-8975,475)","0","logical_power","I60";
;
HDL_POWER"P3V3_AUX"
CDS_LIB"logical_power";
"A"4;
%"UNIVERSAL_GND"
"1","(-10000,-800)","0","logical_power","I61";
;
HDL_POWER"GND"
CDS_LIB"logical_power";
"A"14;
%"Q_RES"
"1","(-7600,1875)","0","pure_quanta","I66";
;
PART_NUMBER"CS21002FB06"
MATERIAL"CHIP"
VALUE"1K"
$LOCATION"R4053"
CDS_LIB"pure_quanta"
PACK_TYPE"0402LF"
WATTAGE"1/16W"
TOLERANCE"1%"
CDS_LOCATION"R4053"
$SEC"1"
CDS_SEC"1";
"B"
$PN"2"22;
"A"
$PN"1"44;
%"Q_RES"
"1","(-7600,-200)","0","pure_quanta","I67";
;
PART_NUMBER"CS21002FB06"
VALUE"1K"
MATERIAL"CHIP"
$LOCATION"R4054"
CDS_LIB"pure_quanta"
TOLERANCE"1%"
WATTAGE"1/16W"
PACK_TYPE"0402LF"
CDS_LOCATION"R4054"
$SEC"1"
CDS_SEC"1";
"B"
$PN"2"16;
"A"
$PN"1"25;
%"UNIVERSAL_GND"
"1","(-10000,1275)","0","logical_power","I8";
;
HDL_POWER"GND"
CDS_LIB"logical_power";
"A"20;
%"GTL2014PW"
"1","(-9475,-2300)","2","pure_quanta","I80";
;
PART_NUMBER"AL002014K01"
MATERIAL"IC"
VALUE"GTL2014PW"
PART_TYPE"SMLF"
$LOCATION"U306"
SEC_TYPE""
CDS_LIB"pure_quanta"
CDS_LMAN_SYM_OUTLINE"-250,350,250,-350"
NEEDS_NO_SIZE"TRUE"
CDS_LOCATION"U306"
SEC"1";
"VCC"
$PN"14"1;
"VREF"
$PN"4"35;
"DIR"
$PN"1"50;
"A0"
$PN"13"48;
"A1"
$PN"12"49;
"A2"
$PN"10"37;
"A3"
$PN"9"36;
"GND_0"
$PN"7"19;
"GND_1"
$PN"8"19;
"GND_2"
$PN"11"19;
"B3"
$PN"6"23;
"B2"
$PN"5"34;
"B1"
$PN"3"61;
"B0"
$PN"2"51;
%"Q_CAP"
"1","(-8825,-1675)","0","pure_quanta","I83";
;
PART_NUMBER"CH5104KEB02"
VALUE"1UF"
PACK_TYPE"C0402"
MATERIAL"X6S"
VOLTAGE"25V"
TOLERANCE"10%"
$LOCATION"C2248"
CDS_LIB"pure_quanta"
CDS_LOCATION"C2248"
$SEC"1"
CDS_SEC"1";
"B"
$PN"2"18;
"A"
$PN"1"1;
%"UNIVERSAL_POWER"
"1","(-8975,-1425)","0","logical_power","I84";
;
HDL_POWER"P3V3"
CDS_LIB"logical_power";
"A"1;
%"UNIVERSAL_GND"
"1","(-7125,-2175)","2","logical_power","I89";
;
HDL_POWER"GND"
CDS_LIB"logical_power";
"A"17;
%"Q_CAP"
"1","(-8825,2300)","0","pure_quanta","I9";
;
PART_NUMBER"CH5104KEB02"
TOLERANCE"10%"
MATERIAL"X6S"
VOLTAGE"25V"
VALUE"1UF"
PACK_TYPE"C0402"
$LOCATION"C2246"
CDS_LIB"pure_quanta"
CDS_LOCATION"C2246"
$SEC"1"
CDS_SEC"1";
"B"
$PN"2"21;
"A"
$PN"1"9;
%"Q_RES"
"1","(-7575,-2150)","0","pure_quanta","I91";
;
PART_NUMBER"CS21002FB06"
VALUE"1K"
MATERIAL"CHIP"
WATTAGE"1/16W"
TOLERANCE"1%"
PACK_TYPE"0402LF"
$LOCATION"R4055"
CDS_LIB"pure_quanta"
CDS_LOCATION"R4055"
$SEC"1"
CDS_SEC"1";
"B"
$PN"2"17;
"A"
$PN"1"50;
%"Q_RES"
"1","(-5800,-2300)","0","pure_quanta","I94";
;
PART_NUMBER"CS03322FB03"
MATERIAL"CHIP"
VALUE"33.2"
$LOCATION"R4051"
WATTAGE"1/16W"
TOLERANCE"1%"
PACK_TYPE"0402LF"
CDS_LIB"pure_quanta"
CDS_LOCATION"R4051"
$SEC"1"
CDS_SEC"1";
"B"
$PN"2"39;
"A"
$PN"1"37;
%"UNIVERSAL_GND"
"1","(-8825,-1900)","0","logical_power","I96";
;
HDL_POWER"GND"
CDS_LIB"logical_power";
"A"18;
%"UNIVERSAL_GND"
"1","(-10000,-2700)","0","logical_power","I97";
;
CDS_LIB"logical_power"
HDL_POWER"GND";
"A"19;
END.
